(kicad_pcb
	(version 20241229)
	(generator "pcbnew")
	(generator_version "9.0")
	(general
		(thickness 1.63)
		(legacy_teardrops no)
	)
	(paper "A4")
	(title_block
		(title "CM4 Baseboard")
		(date "2026-01-05")
		(rev "1.1.1")
		(company "Antmicro Ltd")
		(comment 1 "www.antmicro.com")
		(comment 9 "footprints 160-164 of 506")
	)
	(layers
		(0 "F.Cu" signal)
		(4 "In1.Cu" power)
		(6 "In2.Cu" power)
		(8 "In3.Cu" signal)
		(10 "In4.Cu" signal)
		(2 "B.Cu" signal)
		(9 "F.Adhes" user "F.Adhesive")
		(11 "B.Adhes" user "B.Adhesive")
		(13 "F.Paste" user)
		(15 "B.Paste" user)
		(5 "F.SilkS" user "F.Silkscreen")
		(7 "B.SilkS" user "B.Silkscreen")
		(1 "F.Mask" user)
		(3 "B.Mask" user)
		(17 "Dwgs.User" user "User.Drawings")
		(19 "Cmts.User" user "User.Comments")
		(21 "Eco1.User" user "User.Eco1")
		(23 "Eco2.User" user "User.Eco2")
		(25 "Edge.Cuts" user)
		(27 "Margin" user)
		(31 "F.CrtYd" user "F.Courtyard")
		(29 "B.CrtYd" user "B.Courtyard")
		(35 "F.Fab" user)
		(33 "B.Fab" user)
	)
	(footprint "antmicro-footprints:LED_0603_1608Metric_G"
		(layer "F.Cu")
		(at 73.712962 156.1215 180)
		(descr "LED SMD 0603 Green")
		(tags "LED SMD 0603 Green")
		(property "Reference" "D302"
			(at 6.095 0.005 0)
			(layer "F.SilkS")
			(effects
				(font
					(size 0.7 0.7)
					(thickness 0.15)
				)
				(justify right bottom)
			)
		)
		(property "Value" "LED_G_0603_KP-1608CGCK"
			(at -0.001 1.599 0)
			(layer "F.Fab")
			(effects
				(font
					(size 0.7 0.7)
					(thickness 0.15)
				)
				(justify right bottom)
			)
		)
		(property "Datasheet" "http://www.kingbright.com/attachments/file/psearch//000/00/00/KP-1608CGCK(Ver.23B).pdf"
			(at 0 0 180)
			(layer "F.Fab")
			(hide yes)
			(effects
				(font
					(size 1.27 1.27)
					(thickness 0.15)
				)
			)
		)
		(property "MPN" "KP-1608CGCK"
			(at 0 0 180)
			(unlocked yes)
			(layer "F.Fab")
			(hide yes)
			(effects
				(font
					(size 1 1)
					(thickness 0.15)
				)
			)
		)
		(property "Manufacturer" "Kingbright"
			(at 0 0 180)
			(unlocked yes)
			(layer "F.Fab")
			(hide yes)
			(effects
				(font
					(size 1 1)
					(thickness 0.15)
				)
			)
		)
		(property "Color" "Green"
			(at 0 0 180)
			(unlocked yes)
			(layer "F.Fab")
			(hide yes)
			(effects
				(font
					(size 1 1)
					(thickness 0.15)
				)
			)
		)
		(property "Author" "Antmicro"
			(at 0 0 180)
			(unlocked yes)
			(layer "F.Fab")
			(hide yes)
			(effects
				(font
					(size 1 1)
					(thickness 0.15)
				)
			)
		)
		(property "License" "Apache-2.0"
			(at 0 0 180)
			(unlocked yes)
			(layer "F.Fab")
			(hide yes)
			(effects
				(font
					(size 1 1)
					(thickness 0.15)
				)
			)
		)
		(sheetname "/Supply/")
		(sheetfile "supply.kicad_sch")
		(attr smd)
		(fp_line
			(start 0.22 0.35)
			(end -0.22 0.35)
			(stroke
				(width 0.15)
				(type solid)
			)
			(layer "F.SilkS")
		)
		(fp_line
			(start 0.22 -0.35)
			(end -0.22 -0.35)
			(stroke
				(width 0.15)
				(type solid)
			)
			(layer "F.SilkS")
		)
		(fp_line
			(start 0.105328 0.201008)
			(end 0.105328 -0.198992)
			(stroke
				(width 0.1)
				(type solid)
			)
			(layer "F.SilkS")
		)
		(fp_line
			(start 0.105328 0.201008)
			(end -0.094672 0.001008)
			(stroke
				(width 0.1)
				(type solid)
			)
			(layer "F.SilkS")
		)
		(fp_line
			(start 0.105328 0.001008)
			(end 0.24 0.001)
			(stroke
				(width 0.1)
				(type solid)
			)
			(layer "F.SilkS")
		)
		(fp_line
			(start -0.094672 0.201008)
			(end -0.094672 -0.198992)
			(stroke
				(width 0.1)
				(type solid)
			)
			(layer "F.SilkS")
		)
		(fp_line
			(start -0.094672 0.001008)
			(end 0.105328 -0.198992)
			(stroke
				(width 0.1)
				(type solid)
			)
			(layer "F.SilkS")
		)
		(fp_line
			(start -0.094672 0.001008)
			(end -0.24 0.001008)
			(stroke
				(width 0.1)
				(type solid)
			)
			(layer "F.SilkS")
		)
		(fp_line
			(start -1.18 -0.319)
			(end -1.18 0.321)
			(stroke
				(width 0.15)
				(type solid)
			)
			(layer "F.SilkS")
		)
		(fp_rect
			(start 1.25 0.65)
			(end -1.25 -0.65)
			(stroke
				(width 0.05)
				(type solid)
			)
			(fill no)
			(layer "F.CrtYd")
		)
		(fp_line
			(start 0.599 0)
			(end 0.201 0)
			(stroke
				(width 0.15)
				(type solid)
			)
			(layer "F.Fab")
		)
		(fp_line
			(start 0.201 0.2)
			(end 0.201 0)
			(stroke
				(width 0.15)
				(type solid)
			)
			(layer "F.Fab")
		)
		(fp_line
			(start 0.201 0)
			(end 0.201 -0.202)
			(stroke
				(width 0.15)
				(type solid)
			)
			(layer "F.Fab")
		)
		(fp_line
			(start 0.201 -0.202)
			(end -0.101 0)
			(stroke
				(width 0.15)
				(type solid)
			)
			(layer "F.Fab")
		)
		(fp_line
			(start -0.101 0)
			(end 0.201 0.2)
			(stroke
				(width 0.15)
				(type solid)
			)
			(layer "F.Fab")
		)
		(fp_line
			(start -0.199 0.2)
			(end -0.199 0.1)
			(stroke
				(width 0.15)
				(type solid)
			)
			(layer "F.Fab")
		)
		(fp_line
			(start -0.199 0)
			(end -0.597 0)
			(stroke
				(width 0.15)
				(type solid)
			)
			(layer "F.Fab")
		)
		(fp_line
			(start -0.199 -0.202)
			(end -0.199 0.1)
			(stroke
				(width 0.15)
				(type solid)
			)
			(layer "F.Fab")
		)
		(fp_rect
			(start 0.848 0.4)
			(end -0.85 -0.402)
			(stroke
				(width 0.15)
				(type solid)
			)
			(fill no)
			(layer "F.Fab")
		)
		(fp_text user "Author: Antmicro"
			(at -1.4224 4.799 180)
			(layer "F.Fab")
			(effects
				(font
					(size 0.7 0.7)
					(thickness 0.15)
				)
				(justify left bottom)
			)
		)
		(fp_text user "License: Apache-2.0"
			(at -1.4224 3.599 180)
			(layer "F.Fab")
			(effects
				(font
					(size 0.7 0.7)
					(thickness 0.15)
				)
				(justify left bottom)
			)
		)
		(fp_text user "${REFERENCE}"
			(at -1.4224 5.999 180)
			(layer "F.Fab")
			(effects
				(font
					(size 0.7 0.7)
					(thickness 0.15)
				)
				(justify left bottom)
			)
		)
		(pad "1" smd roundrect
			(at -0.7 0)
			(size 0.8 1)
			(layers "F.Cu" "F.Mask" "F.Paste")
			(roundrect_rratio 0.2)
			(net 3 "GND")
			(pinfunction "C")
			(pintype "passive")
		)
		(pad "2" smd roundrect
			(at 0.7 0)
			(size 0.8 1)
			(layers "F.Cu" "F.Mask" "F.Paste")
			(roundrect_rratio 0.2)
			(net 473 "Net-(D302-A)")
			(pinfunction "A")
			(pintype "passive")
		)
	)
	(footprint "antmicro-footprints:R_0402_1005Metric"
		(layer "F.Cu")
		(at 123.805476 162.7165)
		(descr "Resistor SMD 0402")
		(tags "resistor SMD 0402")
		(property "Reference" "R504"
			(at -3.837514 0.4 0)
			(layer "F.SilkS")
			(effects
				(font
					(size 0.7 0.7)
					(thickness 0.15)
				)
				(justify left bottom)
			)
		)
		(property "Value" "R_10k_0402"
			(at -1.011843 1.772047 0)
			(layer "F.Fab")
			(effects
				(font
					(size 0.7 0.7)
					(thickness 0.15)
				)
				(justify left bottom)
			)
		)
		(property "Datasheet" "https://www.bourns.com/docs/product-datasheets/cr.pdf"
			(at 0 0 0)
			(layer "F.Fab")
			(hide yes)
			(effects
				(font
					(size 1.27 1.27)
					(thickness 0.15)
				)
			)
		)
		(property "Manufacturer" "Bourns"
			(at 0 0 0)
			(unlocked yes)
			(layer "F.Fab")
			(hide yes)
			(effects
				(font
					(size 1 1)
					(thickness 0.15)
				)
			)
		)
		(property "MPN" "CR0402-FX-1002GLF"
			(at 0 0 0)
			(unlocked yes)
			(layer "F.Fab")
			(hide yes)
			(effects
				(font
					(size 1 1)
					(thickness 0.15)
				)
			)
		)
		(property "Val" "10k"
			(at 0 0 0)
			(unlocked yes)
			(layer "F.Fab")
			(hide yes)
			(effects
				(font
					(size 1 1)
					(thickness 0.15)
				)
			)
		)
		(property "License" "Apache-2.0"
			(at 0 0 0)
			(unlocked yes)
			(layer "F.Fab")
			(hide yes)
			(effects
				(font
					(size 1 1)
					(thickness 0.15)
				)
			)
		)
		(property "Author" "Antmicro"
			(at 0 0 0)
			(unlocked yes)
			(layer "F.Fab")
			(hide yes)
			(effects
				(font
					(size 1 1)
					(thickness 0.15)
				)
			)
		)
		(property "Tolerance" "1%"
			(at 0 0 0)
			(unlocked yes)
			(layer "F.Fab")
			(hide yes)
			(effects
				(font
					(size 1 1)
					(thickness 0.15)
				)
			)
		)
		(sheetname "/NVMe & microSD/")
		(sheetfile "nvme-micro-sd.kicad_sch")
		(attr smd)
		(fp_rect
			(start -0.925 -0.47)
			(end 0.925 0.47)
			(stroke
				(width 0.05)
				(type default)
			)
			(fill no)
			(layer "F.CrtYd")
		)
		(fp_rect
			(start -0.5 -0.25)
			(end 0.5 0.25)
			(stroke
				(width 0.15)
				(type solid)
			)
			(fill no)
			(layer "F.Fab")
		)
		(fp_text user "License: Apache-2.0"
			(at -0.95 5.169 0)
			(layer "F.Fab")
			(effects
				(font
					(size 0.7 0.7)
					(thickness 0.15)
				)
				(justify left bottom)
			)
		)
		(fp_text user "Author: Antmicro"
			(at -0.95 4.169 0)
			(layer "F.Fab")
			(effects
				(font
					(size 0.7 0.7)
					(thickness 0.15)
				)
				(justify left bottom)
			)
		)
		(fp_text user "${REFERENCE}"
			(at -0.95 3.168 0)
			(layer "F.Fab")
			(effects
				(font
					(size 0.7 0.7)
					(thickness 0.15)
				)
				(justify left bottom)
			)
		)
		(pad "1" smd roundrect
			(at -0.48 0)
			(size 0.59 0.64)
			(layers "F.Cu" "F.Mask" "F.Paste")
			(roundrect_rratio 0.25)
			(net 9 "+3V3")
			(pintype "passive")
		)
		(pad "2" smd roundrect
			(at 0.48 0)
			(size 0.59 0.64)
			(layers "F.Cu" "F.Mask" "F.Paste")
			(roundrect_rratio 0.25)
			(net 5 "/Compute module/SDIO.D1")
			(pintype "passive")
		)
	)
	(footprint "antmicro-footprints:Nexperia_DFN-10_2.5x1mm_P0.5mm"
		(layer "F.Cu")
		(at 106.112462 125.349367)
		(property "Reference" "D706"
			(at -1.3195 1.65 0)
			(layer "F.SilkS")
			(effects
				(font
					(size 0.7 0.7)
					(thickness 0.15)
				)
				(justify left bottom)
			)
		)
		(property "Value" "PUSB3F96X_PASS"
			(at -0.016 1.705 0)
			(layer "F.Fab")
			(effects
				(font
					(size 0.7 0.7)
					(thickness 0.15)
				)
				(justify left bottom)
			)
		)
		(property "Datasheet" "https://mouser.com/datasheet/2/916/PUSB3F96-1600324.pdf"
			(at 0 0 0)
			(layer "F.Fab")
			(hide yes)
			(effects
				(font
					(size 1.27 1.27)
					(thickness 0.15)
				)
			)
		)
		(property "Manufacturer" "Nexperia"
			(at 0 0 0)
			(unlocked yes)
			(layer "F.Fab")
			(hide yes)
			(effects
				(font
					(size 1 1)
					(thickness 0.15)
				)
			)
		)
		(property "MPN" "PUSB3F96X"
			(at 0 0 0)
			(unlocked yes)
			(layer "F.Fab")
			(hide yes)
			(effects
				(font
					(size 1 1)
					(thickness 0.15)
				)
			)
		)
		(property "Author" "Antmicro"
			(at 0 0 0)
			(unlocked yes)
			(layer "F.Fab")
			(hide yes)
			(effects
				(font
					(size 1 1)
					(thickness 0.15)
				)
			)
		)
		(property "License" "Apache-2.0"
			(at 0 0 0)
			(unlocked yes)
			(layer "F.Fab")
			(hide yes)
			(effects
				(font
					(size 1 1)
					(thickness 0.15)
				)
			)
		)
		(sheetname "/Display/")
		(sheetfile "display.kicad_sch")
		(attr smd)
		(fp_line
			(start -1.375 -0.4)
			(end -1.375 0.4)
			(stroke
				(width 0.15)
				(type solid)
			)
			(layer "F.SilkS")
		)
		(fp_line
			(start 1.375 0.4)
			(end 1.375 -0.4)
			(stroke
				(width 0.15)
				(type solid)
			)
			(layer "F.SilkS")
		)
		(fp_circle
			(center -1.4 0.7)
			(end -1.349 0.7)
			(stroke
				(width 0.15)
				(type solid)
			)
			(fill yes)
			(layer "F.SilkS")
		)
		(fp_rect
			(start -1.4 -0.725)
			(end 1.4 0.725)
			(stroke
				(width 0.05)
				(type solid)
			)
			(fill no)
			(layer "F.CrtYd")
		)
		(fp_line
			(start -1.25 -0.5)
			(end -1.25 0.15)
			(stroke
				(width 0.15)
				(type solid)
			)
			(layer "F.Fab")
		)
		(fp_line
			(start -1.25 0.15)
			(end -0.9 0.5)
			(stroke
				(width 0.15)
				(type solid)
			)
			(layer "F.Fab")
		)
		(fp_line
			(start -0.9 0.5)
			(end 1.25 0.5)
			(stroke
				(width 0.15)
				(type solid)
			)
			(layer "F.Fab")
		)
		(fp_line
			(start 1.25 -0.5)
			(end -1.25 -0.5)
			(stroke
				(width 0.15)
				(type solid)
			)
			(layer "F.Fab")
		)
		(fp_line
			(start 1.25 0.5)
			(end 1.25 -0.5)
			(stroke
				(width 0.15)
				(type solid)
			)
			(layer "F.Fab")
		)
		(fp_text user "Author: Antmicro"
			(at -1.367 4.905 0)
			(layer "F.Fab")
			(effects
				(font
					(size 0.7 0.7)
					(thickness 0.15)
				)
				(justify left bottom)
			)
		)
		(fp_text user "License: Apache-2.0"
			(at -1.367 6.105 0)
			(layer "F.Fab")
			(effects
				(font
					(size 0.7 0.7)
					(thickness 0.15)
				)
				(justify left bottom)
			)
		)
		(fp_text user "${REFERENCE}"
			(at -1.367 3.704 0)
			(layer "F.Fab")
			(effects
				(font
					(size 0.7 0.7)
					(thickness 0.15)
				)
				(justify left bottom)
			)
		)
		(pad "1" smd rect
			(at -1 0.3875)
			(size 0.2 0.475)
			(layers "F.Cu" "F.Mask" "F.Paste")
			(net 16 "/Compute module/HDMI.D2_P")
			(pinfunction "CH1")
			(pintype "passive")
			(solder_mask_margin 0.05)
		)
		(pad "2" smd rect
			(at -0.5 0.3875)
			(size 0.2 0.475)
			(layers "F.Cu" "F.Mask" "F.Paste")
			(net 15 "/Compute module/HDMI.D2_N")
			(pinfunction "CH2")
			(pintype "passive")
			(solder_mask_margin 0.05)
		)
		(pad "3" smd rect
			(at 0 0.3875)
			(size 0.2 0.475)
			(layers "F.Cu" "F.Mask" "F.Paste")
			(net 3 "GND")
			(pinfunction "GND")
			(pintype "passive")
			(solder_mask_margin 0.05)
		)
		(pad "4" smd rect
			(at 0.5 0.3875)
			(size 0.2 0.475)
			(layers "F.Cu" "F.Mask" "F.Paste")
			(net 14 "/Compute module/HDMI.D1_P")
			(pinfunction "CH3")
			(pintype "passive")
			(solder_mask_margin 0.05)
		)
		(pad "5" smd rect
			(at 1 0.3875)
			(size 0.2 0.475)
			(layers "F.Cu" "F.Mask" "F.Paste")
			(net 13 "/Compute module/HDMI.D1_N")
			(pinfunction "CH4")
			(pintype "passive")
			(solder_mask_margin 0.05)
		)
		(pad "6" smd rect
			(at 1 -0.3875)
			(size 0.2 0.475)
			(layers "F.Cu" "F.Mask" "F.Paste")
			(net 13 "/Compute module/HDMI.D1_N")
			(pinfunction "CH4")
			(pintype "passive")
			(solder_mask_margin 0.05)
		)
		(pad "7" smd rect
			(at 0.5 -0.3875)
			(size 0.2 0.475)
			(layers "F.Cu" "F.Mask" "F.Paste")
			(net 14 "/Compute module/HDMI.D1_P")
			(pinfunction "CH3")
			(pintype "passive")
			(solder_mask_margin 0.05)
		)
		(pad "8" smd rect
			(at 0 -0.3875)
			(size 0.2 0.475)
			(layers "F.Cu" "F.Mask" "F.Paste")
			(net 3 "GND")
			(pinfunction "GND")
			(pintype "passive")
			(solder_mask_margin 0.05)
		)
		(pad "9" smd rect
			(at -0.501 -0.3875)
			(size 0.2 0.475)
			(layers "F.Cu" "F.Mask" "F.Paste")
			(net 15 "/Compute module/HDMI.D2_N")
			(pinfunction "CH2")
			(pintype "passive")
			(solder_mask_margin 0.05)
		)
		(pad "10" smd rect
			(at -1 -0.3875)
			(size 0.2 0.475)
			(layers "F.Cu" "F.Mask" "F.Paste")
			(net 16 "/Compute module/HDMI.D2_P")
			(pinfunction "CH1")
			(pintype "passive")
			(solder_mask_margin 0.05)
		)
	)
	(footprint "antmicro-footprints:TP_SMD_0.75mm"
		(layer "F.Cu")
		(at 95.1 132.35)
		(property "Reference" "TP908"
			(at 1.8 3.12 0)
			(layer "F.SilkS")
			(effects
				(font
					(size 0.7 0.7)
					(thickness 0.15)
				)
				(justify left bottom)
			)
		)
		(property "Value" "TP_0.75mm_SMD"
			(at 0 1.2 0)
			(layer "F.Fab")
			(effects
				(font
					(size 0.7 0.7)
					(thickness 0.15)
				)
				(justify left bottom)
			)
		)
		(property "MPN" ""
			(at 0 0 0)
			(unlocked yes)
			(layer "F.Fab")
			(hide yes)
			(effects
				(font
					(size 1 1)
					(thickness 0.15)
				)
			)
		)
		(property "Manufacturer" ""
			(at 0 0 0)
			(unlocked yes)
			(layer "F.Fab")
			(hide yes)
			(effects
				(font
					(size 1 1)
					(thickness 0.15)
				)
			)
		)
		(property "Author" "Antmicro"
			(at 0 0 0)
			(unlocked yes)
			(layer "F.Fab")
			(hide yes)
			(effects
				(font
					(size 1 1)
					(thickness 0.15)
				)
			)
		)
		(property "License" "Apache-2.0"
			(at 0 0 0)
			(unlocked yes)
			(layer "F.Fab")
			(hide yes)
			(effects
				(font
					(size 1 1)
					(thickness 0.15)
				)
			)
		)
		(sheetname "/USB/")
		(sheetfile "usb.kicad_sch")
		(attr exclude_from_pos_files exclude_from_bom)
		(fp_circle
			(center 0 0)
			(end 0.475 0)
			(stroke
				(width 0.05)
				(type default)
			)
			(fill no)
			(layer "F.CrtYd")
		)
		(fp_text user "${REFERENCE}"
			(at -0.4 2.7 0)
			(layer "F.Fab")
			(effects
				(font
					(size 0.7 0.7)
					(thickness 0.15)
				)
				(justify left bottom)
			)
		)
		(fp_text user "Author: Antmicro"
			(at -0.4 3.901 0)
			(layer "F.Fab")
			(effects
				(font
					(size 0.7 0.7)
					(thickness 0.15)
				)
				(justify left bottom)
			)
		)
		(fp_text user "License: Apache-2.0"
			(at -0.4 5.101 0)
			(layer "F.Fab")
			(effects
				(font
					(size 0.7 0.7)
					(thickness 0.15)
				)
				(justify left bottom)
			)
		)
		(pad "1" smd circle
			(at 0 0)
			(size 0.75 0.75)
			(layers "F.Cu" "F.Mask")
			(net 385 "Net-(U905-GPIO7)")
			(pinfunction "1")
			(pintype "passive")
		)
	)
	(footprint "antmicro-footprints:SOD-523"
		(layer "F.Cu")
		(at 99.617962 145.3165 180)
		(property "Reference" "D908"
			(at -1.6 -1.45 0)
			(layer "F.SilkS")
			(effects
				(font
					(size 0.7 0.7)
					(thickness 0.15)
				)
				(justify right bottom)
			)
		)
		(property "Value" "RB521S30T1G"
			(at 0 1.499 0)
			(layer "F.Fab")
			(effects
				(font
					(size 0.7 0.7)
					(thickness 0.15)
				)
				(justify right bottom)
			)
		)
		(property "Datasheet" "https://www.onsemi.com/pdf/datasheet/rb521s30t1-d.pdf"
			(at 0 0 180)
			(layer "F.Fab")
			(hide yes)
			(effects
				(font
					(size 1.27 1.27)
					(thickness 0.15)
				)
			)
		)
		(property "MPN" "RB521S30T1G"
			(at 0 0 180)
			(unlocked yes)
			(layer "F.Fab")
			(hide yes)
			(effects
				(font
					(size 1 1)
					(thickness 0.15)
				)
			)
		)
		(property "Manufacturer" "ON Semiconductor"
			(at 0 0 180)
			(unlocked yes)
			(layer "F.Fab")
			(hide yes)
			(effects
				(font
					(size 1 1)
					(thickness 0.15)
				)
			)
		)
		(property "Author" "Antmicro"
			(at 0 0 180)
			(unlocked yes)
			(layer "F.Fab")
			(hide yes)
			(effects
				(font
					(size 1 1)
					(thickness 0.15)
				)
			)
		)
		(property "License" "Apache-2.0"
			(at 0 0 180)
			(unlocked yes)
			(layer "F.Fab")
			(hide yes)
			(effects
				(font
					(size 1 1)
					(thickness 0.15)
				)
			)
		)
		(sheetname "/USB/")
		(sheetfile "usb.kicad_sch")
		(attr smd)
		(fp_line
			(start -0.35 -0.5)
			(end -0.35 0.5)
			(stroke
				(width 0.15)
				(type solid)
			)
			(layer "F.SilkS")
		)
		(fp_rect
			(start -1 -0.6)
			(end 1 0.6)
			(stroke
				(width 0.05)
				(type solid)
			)
			(fill no)
			(layer "F.CrtYd")
		)
		(fp_line
			(start 0.65 -0.425)
			(end 0.65 0.423)
			(stroke
				(width 0.15)
				(type solid)
			)
			(layer "F.Fab")
		)
		(fp_line
			(start -0.35 -0.4)
			(end -0.35 0.4)
			(stroke
				(width 0.15)
				(type solid)
			)
			(layer "F.Fab")
		)
		(fp_line
			(start -0.652 0.423)
			(end 0.65 0.423)
			(stroke
				(width 0.15)
				(type solid)
			)
			(layer "F.Fab")
		)
		(fp_line
			(start -0.652 0.423)
			(end -0.652 -0.425)
			(stroke
				(width 0.15)
				(type solid)
			)
			(layer "F.Fab")
		)
		(fp_line
			(start -0.652 -0.425)
			(end 0.65 -0.425)
			(stroke
				(width 0.15)
				(type solid)
			)
			(layer "F.Fab")
		)
		(fp_text user "${REFERENCE}"
			(at -1.276 3.499 180)
			(layer "F.Fab")
			(effects
				(font
					(size 0.7 0.7)
					(thickness 0.15)
				)
				(justify left bottom)
			)
		)
		(fp_text user "License: Apache-2.0"
			(at -1.276 5.9 180)
			(layer "F.Fab")
			(effects
				(font
					(size 0.7 0.7)
					(thickness 0.15)
				)
				(justify left bottom)
			)
		)
		(fp_text user "Author: Antmicro"
			(at -1.276 4.7 180)
			(layer "F.Fab")
			(effects
				(font
					(size 0.7 0.7)
					(thickness 0.15)
				)
				(justify left bottom)
			)
		)
		(pad "1" smd roundrect
			(at -0.701 0 180)
			(size 0.5 0.6)
			(layers "F.Cu" "F.Mask" "F.Paste")
			(roundrect_rratio 0.25)
			(net 485 "Net-(D908-C)")
			(pinfunction "C")
			(pintype "passive")
		)
		(pad "2" smd roundrect
			(at 0.699 0 180)
			(size 0.5 0.6)
			(layers "F.Cu" "F.Mask" "F.Paste")
			(roundrect_rratio 0.25)
			(net 143 "/CSI/I_{2}C1.SDA")
			(pinfunction "A")
			(pintype "passive")
		)
	)
)
